# S9S_MB_2U (Grand Teton) — schematic netlist excerpt (pin names and nets, part order shuffled) for the footprints in the layout excerpt that follows; sources: Cadence DE-HDL packaged netlist, KiCad conversion of 03242023_DA0F0TMBIJ0_F0T_Motherboard_J_brd_V01_OCP.brd

R4270  Q_RES  2.2K 5% EMPTY  pkg 0402LF  page 233 : A = P3V3_AUX ; B = SMB_VR_SENSOR_3V3AUX_SDA

Q128  MOSFET_NCH_DUAL  PJT138K IC  pkg SOT363XD  page 146
  S1  = GND
  G1  = GPU_3V3IO_RSVD0_FFU
  D2  = GPU_3V3IO_RSVD0_FFU_ISO
  S2  = GND
  G2  = GPU_3V3IO_RSVD0_FFU_N
  D1  = GPU_3V3IO_RSVD0_FFU_N

(kicad_pcb
	(version 20260206)
	(generator "pcbnew")
	(generator_version "10.0")
	(general
		(thickness 1.6)
		(legacy_teardrops no)
	)
	(paper "A4")
	(title_block
		(title "03242023_DA0F0TMBIJ0_F0T_Motherboard_J_brd_V01_OCP.brd")
		(comment 1 "Grand Teton / footprints 1596-1597 of 6105")
	)
	(layers
		(0 "F.Cu" signal "TOP")
		(4 "In1.Cu" signal "GND")
		(6 "In2.Cu" signal "IN1")
		(8 "In3.Cu" signal "GND1")
		(10 "In4.Cu" signal "IN2")
		(12 "In5.Cu" signal "GND2")
		(14 "In6.Cu" signal "IN3")
		(16 "In7.Cu" signal "GND3")
		(18 "In8.Cu" signal "VCC")
		(20 "In9.Cu" signal "VCC1")
		(22 "In10.Cu" signal "GND4")
		(24 "In11.Cu" signal "IN4")
		(26 "In12.Cu" signal "GND5")
		(28 "In13.Cu" signal "IN5")
		(30 "In14.Cu" signal "GND6")
		(32 "In15.Cu" signal "IN6")
		(34 "In16.Cu" signal "GND7")
		(2 "B.Cu" signal "BOTTOM")
		(9 "F.Adhes" user "F.Adhesive")
		(11 "B.Adhes" user "B.Adhesive")
		(13 "F.Paste" user "Package Geometry/Pastemask Top")
		(15 "B.Paste" user "Package Geometry/Pastemask Bottom")
		(5 "F.SilkS" user "Ref Des/Silkscreen Top")
		(7 "B.SilkS" user "Ref Des/Silkscreen Bottom")
		(1 "F.Mask" user "Board Geometry/Soldermask Top")
		(3 "B.Mask" user "Board Geometry/Soldermask Bottom")
		(17 "Dwgs.User" user "User.Drawings")
		(19 "Cmts.User" user "User.Comments")
		(21 "Eco1.User" user "User.Eco1")
		(23 "Eco2.User" user "User.Eco2")
		(25 "Edge.Cuts" user "Board Geometry/Outline")
		(27 "Margin" user)
		(31 "F.CrtYd" user "Package Geometry/Place Bound Top")
		(29 "B.CrtYd" user "Package Geometry/Place Bound Bottom")
		(35 "F.Fab" user "Ref Des/Assembly Top")
		(33 "B.Fab" user "Ref Des/Assembly Bottom")
	)
	(footprint ""
		(layer "F.Cu")
		(at 70.358 -114.772948 180)
		(property "Reference" "R4270"
			(at 0 0 180)
			(layer "F.SilkS")
			(hide yes)
			(effects
				(font
					(size 1.27 1.27)
				)
			)
		)
		(property "Value" ""
			(at 0 0 180)
			(layer "F.Fab")
			(effects
				(font
					(size 1.27 1.27)
				)
			)
		)
		(duplicate_pad_numbers_are_jumpers no)
		(fp_line
			(start 0.7874 0.4064)
			(end -0.7874 0.4064)
			(stroke
				(width 0.1524)
				(type default)
			)
			(layer "F.SilkS")
		)
		(fp_line
			(start 0.7874 -0.4064)
			(end 0.7874 0.4064)
			(stroke
				(width 0.1524)
				(type default)
			)
			(layer "F.SilkS")
		)
		(fp_line
			(start -0.7874 0.4064)
			(end -0.7874 -0.4064)
			(stroke
				(width 0.1524)
				(type default)
			)
			(layer "F.SilkS")
		)
		(fp_line
			(start -0.7874 -0.4064)
			(end 0.7874 -0.4064)
			(stroke
				(width 0.1524)
				(type default)
			)
			(layer "F.SilkS")
		)
		(fp_line
			(start 0.67945 0.3048)
			(end 0.120396 0.3048)
			(stroke
				(width 0.1)
				(type default)
			)
			(layer "F.Fab")
		)
		(fp_line
			(start 0.67945 -0.3048)
			(end 0.67945 0.3048)
			(stroke
				(width 0.1)
				(type default)
			)
			(layer "F.Fab")
		)
		(fp_line
			(start 0.12065 -0.2794)
			(end 0.12065 -0.3048)
			(stroke
				(width 0.1)
				(type default)
			)
			(layer "F.Fab")
		)
		(fp_line
			(start 0.12065 -0.3048)
			(end 0.67945 -0.3048)
			(stroke
				(width 0.1)
				(type default)
			)
			(layer "F.Fab")
		)
		(fp_line
			(start 0.120396 0.3048)
			(end 0.120396 0.2794)
			(stroke
				(width 0.1)
				(type default)
			)
			(layer "F.Fab")
		)
		(fp_line
			(start 0.120396 0.2794)
			(end -0.12065 0.2794)
			(stroke
				(width 0.1)
				(type default)
			)
			(layer "F.Fab")
		)
		(fp_line
			(start -0.12065 0.3048)
			(end -0.67945 0.3048)
			(stroke
				(width 0.1)
				(type default)
			)
			(layer "F.Fab")
		)
		(fp_line
			(start -0.12065 0.2794)
			(end -0.12065 0.3048)
			(stroke
				(width 0.1)
				(type default)
			)
			(layer "F.Fab")
		)
		(fp_line
			(start -0.12065 -0.2794)
			(end 0.12065 -0.2794)
			(stroke
				(width 0.1)
				(type default)
			)
			(layer "F.Fab")
		)
		(fp_line
			(start -0.12065 -0.305054)
			(end -0.12065 -0.2794)
			(stroke
				(width 0.1)
				(type default)
			)
			(layer "F.Fab")
		)
		(fp_line
			(start -0.67945 0.3048)
			(end -0.67945 -0.305054)
			(stroke
				(width 0.1)
				(type default)
			)
			(layer "F.Fab")
		)
		(fp_line
			(start -0.67945 -0.305054)
			(end -0.12065 -0.305054)
			(stroke
				(width 0.1)
				(type default)
			)
			(layer "F.Fab")
		)
		(pad "1" smd circle
			(at -0.40005 0 180)
			(size 0 0)
			(layers "F.Cu" "F.Mask" "F.Paste")
			(net "P3V3_AUX")
		)
		(pad "2" smd circle
			(at 0.40005 0 180)
			(size 0 0)
			(layers "F.Cu" "F.Mask" "F.Paste")
			(net "SMB_VR_SENSOR_3V3AUX_SDA")
		)
	)
	(footprint ""
		(layer "F.Cu")
		(at 303.2506 -424.08475 90)
		(property "Reference" "Q128"
			(at -7.87908 5.816092 90)
			(unlocked yes)
			(layer "F.SilkS")
			(effects
				(font
					(size 0.7874 0.5842)
					(thickness 0.1524)
				)
				(justify left)
			)
		)
		(property "Value" ""
			(at 0 0 90)
			(layer "F.Fab")
			(effects
				(font
					(size 1.27 1.27)
				)
			)
		)
		(duplicate_pad_numbers_are_jumpers no)
		(fp_line
			(start 1.332738 -1.100074)
			(end 1.332738 1.100074)
			(stroke
				(width 0.1524)
				(type default)
			)
			(layer "F.SilkS")
		)
		(fp_line
			(start 0.4826 -1.100074)
			(end 1.332738 -1.100074)
			(stroke
				(width 0.1524)
				(type default)
			)
			(layer "F.SilkS")
		)
		(fp_line
			(start -0.4826 -1.100074)
			(end 0 -0.541274)
			(stroke
				(width 0.1524)
				(type default)
			)
			(layer "F.SilkS")
		)
		(fp_line
			(start -1.332738 -1.100074)
			(end -0.4826 -1.100074)
			(stroke
				(width 0.1524)
				(type default)
			)
			(layer "F.SilkS")
		)
		(fp_line
			(start 0 -0.541274)
			(end 0.4826 -1.100074)
			(stroke
				(width 0.1524)
				(type default)
			)
			(layer "F.SilkS")
		)
		(fp_line
			(start 1.332738 1.100074)
			(end -1.332738 1.100074)
			(stroke
				(width 0.1524)
				(type default)
			)
			(layer "F.SilkS")
		)
		(fp_line
			(start -1.332738 1.100074)
			(end -1.332738 -1.100074)
			(stroke
				(width 0.1524)
				(type default)
			)
			(layer "F.SilkS")
		)
		(fp_poly
			(pts
				(xy -2.37236 -1.427734) (xy -1.670304 -1.076706) (xy -2.37236 -0.725678)
			)
			(stroke
				(width 0)
				(type default)
			)
			(fill yes)
			(layer "F.SilkS")
		)
		(fp_line
			(start 0.674878 -1.100074)
			(end 0.674878 1.100074)
			(stroke
				(width 0.1)
				(type default)
			)
			(layer "F.Fab")
		)
		(fp_line
			(start -0.674878 -1.100074)
			(end 0.674878 -1.100074)
			(stroke
				(width 0.1)
				(type default)
			)
			(layer "F.Fab")
		)
		(fp_line
			(start 0.674878 1.100074)
			(end -0.674878 1.100074)
			(stroke
				(width 0.1)
				(type default)
			)
			(layer "F.Fab")
		)
		(fp_line
			(start -0.674878 1.100074)
			(end -0.674878 -1.100074)
			(stroke
				(width 0.1)
				(type default)
			)
			(layer "F.Fab")
		)
		(fp_poly
			(pts
				(xy -2.2352 -0.298958) (xy -2.2352 -1.001014) (xy -1.533144 -0.649986)
			)
			(stroke
				(width 0)
				(type default)
			)
			(fill yes)
			(layer "F.Fab")
		)
		(pad "1" smd rect
			(at -0.94996 -0.649986 180)
			(size 0.4318 0.508)
			(layers "F.Cu" "F.Mask" "F.Paste")
			(net "GND")
		)
		(pad "2" smd rect
			(at -0.94996 0 180)
			(size 0.4318 0.508)
			(layers "F.Cu" "F.Mask" "F.Paste")
			(net "GPU_3V3IO_RSVD0_FFU")
		)
		(pad "3" smd rect
			(at -0.94996 0.649986 180)
			(size 0.4318 0.508)
			(layers "F.Cu" "F.Mask" "F.Paste")
			(net "GPU_3V3IO_RSVD0_FFU_ISO")
		)
		(pad "4" smd rect
			(at 0.94996 0.649986 180)
			(size 0.4318 0.508)
			(layers "F.Cu" "F.Mask" "F.Paste")
			(net "GND")
		)
		(pad "5" smd rect
			(at 0.94996 0 180)
			(size 0.4318 0.508)
			(layers "F.Cu" "F.Mask" "F.Paste")
			(net "GPU_3V3IO_RSVD0_FFU_N")
		)
		(pad "6" smd rect
			(at 0.94996 -0.649986 180)
			(size 0.4318 0.508)
			(layers "F.Cu" "F.Mask" "F.Paste")
			(net "GPU_3V3IO_RSVD0_FFU_N")
		)
	)
)
